# T6G (Grand Teton) — schematic netlist excerpt (pin names and nets, part order shuffled) for the footprints in the layout excerpt that follows; sources: Cadence DE-HDL packaged netlist, KiCad conversion of 04192023_DAF0TMB3IC0_F0TG_MB_C_brd_V02_OCP.brd

C747  Q_CAP_DIFFBUS  DIFF BUS_0.22UF 6.3V 20% X6S  pkg C0201  page 66 : \1\ = P5E_CPU1_P2_TX_C_DP<13> ; \2\ = P5E_CPU1_P2_TX_DP<13>
PR835  Q_RES  0 5% CHIP  pkg 0402LF  page 190 : A = SW_P3V3_AUX_BOOT ; B = SW_P3V3_AUX_BOOT_R
PC5  Q_CAP  0.1UF 25V 10% X7R  pkg 0402  page 207 : A = PVDD11_S3_P0_VINSEN ; B = GND

(kicad_pcb
	(version 20260206)
	(generator "pcbnew")
	(generator_version "10.0")
	(general
		(thickness 1.6)
		(legacy_teardrops no)
	)
	(paper "A4")
	(title_block
		(title "04192023_DAF0TMB3IC0_F0TG_MB_C_brd_V02_OCP.brd")
		(comment 1 "Grand Teton / footprints 3122-3124 of 8354")
	)
	(layers
		(0 "F.Cu" signal "TOP")
		(4 "In1.Cu" signal "GND")
		(6 "In2.Cu" signal "IN1")
		(8 "In3.Cu" signal "GND1")
		(10 "In4.Cu" signal "IN2")
		(12 "In5.Cu" signal "GND2")
		(14 "In6.Cu" signal "IN3")
		(16 "In7.Cu" signal "GND3")
		(18 "In8.Cu" signal "VCC")
		(20 "In9.Cu" signal "VCC1")
		(22 "In10.Cu" signal "GND4")
		(24 "In11.Cu" signal "IN4")
		(26 "In12.Cu" signal "GND5")
		(28 "In13.Cu" signal "IN5")
		(30 "In14.Cu" signal "GND6")
		(32 "In15.Cu" signal "IN6")
		(34 "In16.Cu" signal "GND7")
		(2 "B.Cu" signal "BOTTOM")
		(9 "F.Adhes" user "F.Adhesive")
		(11 "B.Adhes" user "B.Adhesive")
		(13 "F.Paste" user "Package Geometry/Pastemask Top")
		(15 "B.Paste" user "Package Geometry/Pastemask Bottom")
		(5 "F.SilkS" user "Ref Des/Silkscreen Top")
		(7 "B.SilkS" user "Ref Des/Silkscreen Bottom")
		(1 "F.Mask" user "Board Geometry/Soldermask Top")
		(3 "B.Mask" user "Board Geometry/Soldermask Bottom")
		(17 "Dwgs.User" user "User.Drawings")
		(19 "Cmts.User" user "User.Comments")
		(21 "Eco1.User" user "User.Eco1")
		(23 "Eco2.User" user "User.Eco2")
		(25 "Edge.Cuts" user "Board Geometry/Outline")
		(27 "Margin" user)
		(31 "F.CrtYd" user "Package Geometry/Place Bound Top")
		(29 "B.CrtYd" user "Package Geometry/Place Bound Bottom")
		(35 "F.Fab" user "Ref Des/Assembly Top")
		(33 "B.Fab" user "Ref Des/Assembly Bottom")
	)
	(footprint ""
		(layer "F.Cu")
		(at 168.144444 -370.57203 -90)
		(property "Reference" "C747"
			(at 0 0 270)
			(layer "F.SilkS")
			(hide yes)
			(effects
				(font
					(size 1.27 1.27)
				)
			)
		)
		(property "Value" ""
			(at 0 0 270)
			(layer "F.Fab")
			(effects
				(font
					(size 1.27 1.27)
				)
			)
		)
		(duplicate_pad_numbers_are_jumpers no)
		(fp_line
			(start -0.299974 0.150114)
			(end -0.299974 -0.150114)
			(stroke
				(width 0.1)
				(type default)
			)
			(layer "F.Fab")
		)
		(fp_line
			(start 0.299974 0.150114)
			(end -0.299974 0.150114)
			(stroke
				(width 0.1)
				(type default)
			)
			(layer "F.Fab")
		)
		(fp_line
			(start -0.299974 -0.150114)
			(end 0.299974 -0.150114)
			(stroke
				(width 0.1)
				(type default)
			)
			(layer "F.Fab")
		)
		(fp_line
			(start 0.299974 -0.150114)
			(end 0.299974 0.150114)
			(stroke
				(width 0.1)
				(type default)
			)
			(layer "F.Fab")
		)
		(pad "1" smd rect
			(at -0.2667 0 270)
			(size 0.3048 0.381)
			(layers "F.Cu" "F.Mask" "F.Paste")
			(net "P5E_CPU1_P2_TX_C_DP<13>")
		)
		(pad "2" smd rect
			(at 0.2667 0 270)
			(size 0.3048 0.381)
			(layers "F.Cu" "F.Mask" "F.Paste")
			(net "P5E_CPU1_P2_TX_DP<13>")
		)
	)
	(footprint ""
		(layer "F.Cu")
		(at 452.13905 -49.377346 180)
		(property "Reference" "PR835"
			(at 0 0 180)
			(layer "F.SilkS")
			(hide yes)
			(effects
				(font
					(size 1.27 1.27)
				)
			)
		)
		(property "Value" ""
			(at 0 0 180)
			(layer "F.Fab")
			(effects
				(font
					(size 1.27 1.27)
				)
			)
		)
		(duplicate_pad_numbers_are_jumpers no)
		(fp_line
			(start 0.7874 0.4064)
			(end -0.7874 0.4064)
			(stroke
				(width 0.1524)
				(type default)
			)
			(layer "F.SilkS")
		)
		(fp_line
			(start 0.7874 -0.4064)
			(end 0.7874 0.4064)
			(stroke
				(width 0.1524)
				(type default)
			)
			(layer "F.SilkS")
		)
		(fp_line
			(start -0.7874 0.4064)
			(end -0.7874 -0.4064)
			(stroke
				(width 0.1524)
				(type default)
			)
			(layer "F.SilkS")
		)
		(fp_line
			(start -0.7874 -0.4064)
			(end 0.7874 -0.4064)
			(stroke
				(width 0.1524)
				(type default)
			)
			(layer "F.SilkS")
		)
		(fp_line
			(start 0.67945 0.3048)
			(end 0.120396 0.3048)
			(stroke
				(width 0.1)
				(type default)
			)
			(layer "F.Fab")
		)
		(fp_line
			(start 0.67945 -0.3048)
			(end 0.67945 0.3048)
			(stroke
				(width 0.1)
				(type default)
			)
			(layer "F.Fab")
		)
		(fp_line
			(start 0.12065 -0.2794)
			(end 0.12065 -0.3048)
			(stroke
				(width 0.1)
				(type default)
			)
			(layer "F.Fab")
		)
		(fp_line
			(start 0.12065 -0.3048)
			(end 0.67945 -0.3048)
			(stroke
				(width 0.1)
				(type default)
			)
			(layer "F.Fab")
		)
		(fp_line
			(start 0.120396 0.3048)
			(end 0.120396 0.2794)
			(stroke
				(width 0.1)
				(type default)
			)
			(layer "F.Fab")
		)
		(fp_line
			(start 0.120396 0.2794)
			(end -0.12065 0.2794)
			(stroke
				(width 0.1)
				(type default)
			)
			(layer "F.Fab")
		)
		(fp_line
			(start -0.12065 0.3048)
			(end -0.67945 0.3048)
			(stroke
				(width 0.1)
				(type default)
			)
			(layer "F.Fab")
		)
		(fp_line
			(start -0.12065 0.2794)
			(end -0.12065 0.3048)
			(stroke
				(width 0.1)
				(type default)
			)
			(layer "F.Fab")
		)
		(fp_line
			(start -0.12065 -0.2794)
			(end 0.12065 -0.2794)
			(stroke
				(width 0.1)
				(type default)
			)
			(layer "F.Fab")
		)
		(fp_line
			(start -0.12065 -0.305054)
			(end -0.12065 -0.2794)
			(stroke
				(width 0.1)
				(type default)
			)
			(layer "F.Fab")
		)
		(fp_line
			(start -0.67945 0.3048)
			(end -0.67945 -0.305054)
			(stroke
				(width 0.1)
				(type default)
			)
			(layer "F.Fab")
		)
		(fp_line
			(start -0.67945 -0.305054)
			(end -0.12065 -0.305054)
			(stroke
				(width 0.1)
				(type default)
			)
			(layer "F.Fab")
		)
		(pad "1" smd circle
			(at -0.40005 0 180)
			(size 0 0)
			(layers "F.Cu" "F.Mask" "F.Paste")
			(net "SW_P3V3_AUX_BOOT")
		)
		(pad "2" smd circle
			(at 0.40005 0 180)
			(size 0 0)
			(layers "F.Cu" "F.Mask" "F.Paste")
			(net "SW_P3V3_AUX_BOOT_R")
		)
	)
	(footprint ""
		(layer "F.Cu")
		(at 423.610024 -363.78261)
		(property "Reference" "PC5"
			(at 0 0 0)
			(layer "F.SilkS")
			(hide yes)
			(effects
				(font
					(size 1.27 1.27)
				)
			)
		)
		(property "Value" ""
			(at 0 0 0)
			(layer "F.Fab")
			(effects
				(font
					(size 1.27 1.27)
				)
			)
		)
		(duplicate_pad_numbers_are_jumpers no)
		(fp_line
			(start -0.7874 -0.4064)
			(end 0.7874 -0.4064)
			(stroke
				(width 0.1524)
				(type default)
			)
			(layer "F.SilkS")
		)
		(fp_line
			(start -0.7874 0.4064)
			(end -0.7874 -0.4064)
			(stroke
				(width 0.1524)
				(type default)
			)
			(layer "F.SilkS")
		)
		(fp_line
			(start 0.7874 -0.4064)
			(end 0.7874 0.4064)
			(stroke
				(width 0.1524)
				(type default)
			)
			(layer "F.SilkS")
		)
		(fp_line
			(start 0.7874 0.4064)
			(end -0.7874 0.4064)
			(stroke
				(width 0.1524)
				(type default)
			)
			(layer "F.SilkS")
		)
		(fp_line
			(start -0.67945 -0.305054)
			(end -0.12065 -0.305054)
			(stroke
				(width 0.1)
				(type default)
			)
			(layer "F.Fab")
		)
		(fp_line
			(start -0.67945 0.3048)
			(end -0.67945 -0.305054)
			(stroke
				(width 0.1)
				(type default)
			)
			(layer "F.Fab")
		)
		(fp_line
			(start -0.12065 -0.305054)
			(end -0.12065 -0.2794)
			(stroke
				(width 0.1)
				(type default)
			)
			(layer "F.Fab")
		)
		(fp_line
			(start -0.12065 -0.2794)
			(end 0.12065 -0.2794)
			(stroke
				(width 0.1)
				(type default)
			)
			(layer "F.Fab")
		)
		(fp_line
			(start -0.12065 0.2794)
			(end -0.12065 0.3048)
			(stroke
				(width 0.1)
				(type default)
			)
			(layer "F.Fab")
		)
		(fp_line
			(start -0.12065 0.3048)
			(end -0.67945 0.3048)
			(stroke
				(width 0.1)
				(type default)
			)
			(layer "F.Fab")
		)
		(fp_line
			(start 0.120396 0.2794)
			(end -0.12065 0.2794)
			(stroke
				(width 0.1)
				(type default)
			)
			(layer "F.Fab")
		)
		(fp_line
			(start 0.120396 0.3048)
			(end 0.120396 0.2794)
			(stroke
				(width 0.1)
				(type default)
			)
			(layer "F.Fab")
		)
		(fp_line
			(start 0.12065 -0.3048)
			(end 0.67945 -0.3048)
			(stroke
				(width 0.1)
				(type default)
			)
			(layer "F.Fab")
		)
		(fp_line
			(start 0.12065 -0.2794)
			(end 0.12065 -0.3048)
			(stroke
				(width 0.1)
				(type default)
			)
			(layer "F.Fab")
		)
		(fp_line
			(start 0.67945 -0.3048)
			(end 0.67945 0.3048)
			(stroke
				(width 0.1)
				(type default)
			)
			(layer "F.Fab")
		)
		(fp_line
			(start 0.67945 0.3048)
			(end 0.120396 0.3048)
			(stroke
				(width 0.1)
				(type default)
			)
			(layer "F.Fab")
		)
		(pad "1" smd circle
			(at -0.40005 0)
			(size 0 0)
			(layers "F.Cu" "F.Mask" "F.Paste")
			(net "PVDD11_S3_P0_VINSEN")
		)
		(pad "2" smd circle
			(at 0.40005 0)
			(size 0 0)
			(layers "F.Cu" "F.Mask" "F.Paste")
			(net "GND")
		)
	)
)
